FILE_TYPE = CONNECTIVITY;
{Allegro Design Entry HDL 17.4-2019 S026 (4007227) 1/17/2022}
"PAGE_NUMBER" = 30;
0"NC";
1"P1V5_BAT\g";
2"PVDDCR_CPU0_P0\g";
3"PVDDCR_CPU0_P0\g";
4"PVDDCR_CPU1_P0\g";
5"PVDDCR_CPU1_P0\g";
6"PVDDCR_SOC_P0\g";
7"PVDD_33_S5\g";
8"PVDD18_S5_P0\g";
9"PVDD11_S3_P0\g";
10"PVDDCR_SOC_P0\g";
11"PVDDIO_P0\g";
%"GENOA_SP5"
"27","(-2475,3550)","0","pure_quanta","I28";
;
LOCATION"U25"
$SEC"27"
CDS_SEC"27"
PART_TYPE"SMLF"
MATERIAL"IO"
VALUE"SOCKET6096_13568-001"
CDS_LIB"pure_quanta"
CDS_LMAN_SYM_OUTLINE"-500,3075,500,-3075"
NEEDS_NO_SIZE"TRUE"
PART_NUMBER"DGA^6000030";
"VDD_11_S3_CT19"
$PN"CT19"9;
"VDD_11_S3_CT22"
$PN"CT22"9;
"VDD_11_S3_CW4"
$PN"CW4"9;
"VDD_11_S3_CW11"
$PN"CW11"9;
"VDD_11_S3_CW18"
$PN"CW18"9;
"VDD_11_S3_CY22"
$PN"CY22"9;
"VDD_11_S3_DB5"
$PN"DB5"9;
"VDD_11_S3_DB12"
$PN"DB12"9;
"VDD_11_S3_DB19"
$PN"DB19"9;
"VDD_11_S3_DE4"
$PN"DE4"9;
"VDD_11_S3_DE11"
$PN"DE11"9;
"VDD_11_S3_DE18"
$PN"DE18"9;
"VDD_11_S3_DG5"
$PN"DG5"9;
"VDDIO_CT64"
$PN"CT64"11;
"VDDIO_CT71"
$PN"CT71"11;
"VDDIO_CW58"
$PN"CW58"11;
"VDDIO_CW65"
$PN"CW65"11;
"VDDIO_CW72"
$PN"CW72"11;
"VDDIO_CY54"
$PN"CY54"11;
"VDDIO_DB57"
$PN"DB57"11;
"VDDIO_DB64"
$PN"DB64"11;
"VDDIO_DB71"
$PN"DB71"11;
"VDDIO_DE58"
$PN"DE58"11;
"VDDIO_DE65"
$PN"DE65"11;
"VDDIO_DE72"
$PN"DE72"11;
"VDDIO_DG64"
$PN"DG64"11;
"VDDIO_DG71"
$PN"DG71"11;
"VDDBT_RTC_G"
$PN"BN23"1;
"VDDIO_AUDIO"
$PN"BH27"8;
"VDD_33_S5_BP51"
$PN"BP51"7;
"VDD_33_S5_BN52"
$PN"BN52"7;
"VDD_11_S3_CT12"
$PN"CT12"9;
"VDD_18_S5_BB53"
$PN"BB53"8;
"VDD_18_S5_BB51"
$PN"BB51"8;
"VDD_18_S5_BA54"
$PN"BA54"8;
"VDD_18_S5_BA52"
$PN"BA52"8;
"VDD_18_S5_BA50"
$PN"BA50"8;
"VDD_18_S5_AY53"
$PN"AY53"8;
"VDD_18_S5_AY51"
$PN"AY51"8;
"VDD_18_S5_AW54"
$PN"AW54"8;
"VDD_18_S5_AW52"
$PN"AW52"8;
"VDD_18_S5_BC54"
$PN"BC54"8;
"VDD_18_S5_BC52"
$PN"BC52"8;
"VDD_18_S5_AW50"
$PN"AW50"8;
"VDD_18_S5_AV53"
$PN"AV53"8;
"VDD_18_S5_AV51"
$PN"AV51"8;
"VDD_18_S5_AV49"
$PN"AV49"8;
"VDD_18_S5_AU52"
$PN"AU52"8;
"VDD_18_S5_AU50"
$PN"AU50"8;
"VDD_18_S5_AT53"
$PN"AT53"8;
"VDD_18_S5_AT51"
$PN"AT51"8;
"VDD_18_S5_AR54"
$PN"AR54"8;
"VDD_18_S5_AR52"
$PN"AR52"8;
"VDD_18_S5_AU54"
$PN"AU54"8;
"VDD_11_S3_CT5"
$PN"CT5"9;
"VDD_11_S3_CN18"
$PN"CN18"9;
"VDD_11_S3_CN11"
$PN"CN11"9;
"VDD_11_S3_CN4"
$PN"CN4"9;
"VDD_11_S3_CM22"
$PN"CM22"9;
"VDD_11_S3_CK19"
$PN"CK19"9;
"VDD_11_S3_CK12"
$PN"CK12"9;
"VDD_11_S3_CK5"
$PN"CK5"9;
"VDD_11_S3_CJ22"
$PN"CJ22"9;
"VDD_11_S3_CG18"
$PN"CG18"9;
"VDD_11_S3_CG11"
$PN"CG11"9;
"VDD_11_S3_CG4"
$PN"CG4"9;
"VDD_11_S3_CF22"
$PN"CF22"9;
"VDD_11_S3_CD19"
$PN"CD19"9;
"VDD_11_S3_CD12"
$PN"CD12"9;
"VDD_11_S3_CD5"
$PN"CD5"9;
"VDD_11_S3_CB22"
$PN"CB22"9;
"VDD_11_S3_CA18"
$PN"CA18"9;
"VDD_11_S3_CA11"
$PN"CA11"9;
"VDD_11_S3_CA4"
$PN"CA4"9;
"VDD_11_S3_BV22"
$PN"BV22"9;
"VDD_11_S3_BV19"
$PN"BV19"9;
"VDD_11_S3_BV12"
$PN"BV12"9;
"VDD_11_S3_BV5"
$PN"BV5"9;
"VDD_11_S3_BR18"
$PN"BR18"9;
"VDD_11_S3_BR11"
$PN"BR11"9;
"VDD_11_S3_BR4"
$PN"BR4"9;
"VDD_11_S3_BP22"
$PN"BP22"9;
"VDD_11_S3_BN48"
$PN"BN48"9;
"VDD_11_S3_BN44"
$PN"BN44"9;
"VDD_11_S3_BN40"
$PN"BN40"9;
"VDD_11_S3_BN33"
$PN"BN33"9;
"VDD_11_S3_BN29"
$PN"BN29"9;
"VDD_11_S3_BN25"
$PN"BN25"9;
"VDD_11_S3_BM49"
$PN"BM49"9;
"VDD_11_S3_BM47"
$PN"BM47"9;
"VDD_11_S3_BM45"
$PN"BM45"9;
"VDD_11_S3_BM43"
$PN"BM43"9;
"VDD_11_S3_BM41"
$PN"BM41"9;
"VDD_11_S3_BM39"
$PN"BM39"9;
"VDD_11_S3_BM36"
$PN"BM36"9;
"VDD_11_S3_BM34"
$PN"BM34"9;
"VDD_11_S3_BM32"
$PN"BM32"9;
"VDD_11_S3_BM30"
$PN"BM30"9;
"VDD_11_S3_BM28"
$PN"BM28"9;
"VDD_11_S3_BM26"
$PN"BM26"9;
"VDD_11_S3_BM24"
$PN"BM24"9;
"VDD_11_S3_BM22"
$PN"BM22"9;
"VDD_11_S3_BM19"
$PN"BM19"9;
"VDD_11_S3_BM12"
$PN"BM12"9;
"VDD_11_S3_BL48"
$PN"BL48"9;
"VDD_11_S3_BL27"
$PN"BL27"9;
"VDD_11_S3_BL25"
$PN"BL25"9;
"VDD_11_S3_BL23"
$PN"BL23"9;
"VDD_11_S3_BK49"
$PN"BK49"9;
"VDD_11_S3_BK28"
$PN"BK28"9;
"VDD_11_S3_BK26"
$PN"BK26"9;
"VDD_11_S3_BK24"
$PN"BK24"9;
"VDD_11_S3_BK22"
$PN"BK22"9;
"VDD_11_S3_BJ27"
$PN"BJ27"9;
"VDD_11_S3_BJ25"
$PN"BJ25"9;
"VDD_11_S3_BJ23"
$PN"BJ23"9;
"VDD_11_S3_BJ18"
$PN"BJ18"9;
"VDDIO_CT57"
$PN"CT57"11;
"VDDIO_CT54"
$PN"CT54"11;
"VDDIO_CN72"
$PN"CN72"11;
"VDDIO_CN65"
$PN"CN65"11;
"VDDIO_CN58"
$PN"CN58"11;
"VDDIO_CM54"
$PN"CM54"11;
"VDDIO_CK71"
$PN"CK71"11;
"VDDIO_CK64"
$PN"CK64"11;
"VDDIO_CK57"
$PN"CK57"11;
"VDDIO_CJ54"
$PN"CJ54"11;
"VDDIO_CG72"
$PN"CG72"11;
"VDDIO_CG65"
$PN"CG65"11;
"VDDIO_CG58"
$PN"CG58"11;
"VDDIO_CF54"
$PN"CF54"11;
"VDDIO_CD71"
$PN"CD71"11;
"VDDIO_CD64"
$PN"CD64"11;
"VDDIO_CD57"
$PN"CD57"11;
"VDDIO_CB54"
$PN"CB54"11;
"VDDIO_CA72"
$PN"CA72"11;
"VDDIO_CA65"
$PN"CA65"11;
"VDDIO_CA58"
$PN"CA58"11;
"VDDIO_BV71"
$PN"BV71"11;
"VDDIO_BV64"
$PN"BV64"11;
"VDDIO_BV57"
$PN"BV57"11;
"VDDIO_BV54"
$PN"BV54"11;
"VDDIO_BR72"
$PN"BR72"11;
"VDDIO_BR65"
$PN"BR65"11;
"VDDIO_BR58"
$PN"BR58"11;
"VDDIO_BN54"
$PN"BN54"11;
"VDDIO_BM71"
$PN"BM71"11;
"VDDIO_BM64"
$PN"BM64"11;
"VDDIO_BM57"
$PN"BM57"11;
"VDDIO_BM53"
$PN"BM53"11;
"VDDIO_BM51"
$PN"BM51"11;
"VDDIO_BL54"
$PN"BL54"11;
"VDDIO_BL52"
$PN"BL52"11;
"VDDIO_BL50"
$PN"BL50"11;
"VDDIO_BK53"
$PN"BK53"11;
"VDDIO_BK51"
$PN"BK51"11;
"VDDIO_BJ72"
$PN"BJ72"11;
"VDDIO_BJ65"
$PN"BJ65"11;
"VDDIO_BJ58"
$PN"BJ58"11;
"VDDIO_BJ54"
$PN"BJ54"11;
"VDDIO_BJ52"
$PN"BJ52"11;
"VDDIO_BJ50"
$PN"BJ50"11;
"VDDIO_BH53"
$PN"BH53"11;
"VDDIO_BH51"
$PN"BH51"11;
"VDDIO_BG54"
$PN"BG54"11;
"VDDIO_BG52"
$PN"BG52"11;
"VDDIO_BG50"
$PN"BG50"11;
"VDDIO_BF71"
$PN"BF71"11;
"VDDIO_BF64"
$PN"BF64"11;
"VDDIO_BF57"
$PN"BF57"11;
"VDDIO_BF53"
$PN"BF53"11;
"VDDIO_BF51"
$PN"BF51"11;
"VDDIO_BD54"
$PN"BD54"11;
"VDDIO_BD52"
$PN"BD52"11;
"VDDIO_BD50"
$PN"BD50"11;
"VDDIO_BA72"
$PN"BA72"11;
"VDDIO_BA65"
$PN"BA65"11;
"VDDIO_BA58"
$PN"BA58"11;
"VDDIO_AV71"
$PN"AV71"11;
"VDDIO_AV64"
$PN"AV64"11;
"VDDIO_AV57"
$PN"AV57"11;
"VDDIO_AR72"
$PN"AR72"11;
"VDDIO_AR65"
$PN"AR65"11;
"VDDIO_AR58"
$PN"AR58"11;
"VDDIO_AM71"
$PN"AM71"11;
"VDDIO_AM64"
$PN"AM64"11;
"VDDIO_AM57"
$PN"AM57"11;
"VDDIO_AM54"
$PN"AM54"11;
"VDDIO_AJ72"
$PN"AJ72"11;
"VDDIO_AJ65"
$PN"AJ65"11;
"VDDIO_AJ58"
$PN"AJ58"11;
"VDDIO_AH54"
$PN"AH54"11;
"VDDIO_AF71"
$PN"AF71"11;
"VDDIO_AF64"
$PN"AF64"11;
"VDDIO_AF57"
$PN"AF57"11;
"VDDIO_AD54"
$PN"AD54"11;
"VDDIO_AC72"
$PN"AC72"11;
"VDDIO_AC65"
$PN"AC65"11;
"VDDIO_AC58"
$PN"AC58"11;
"VDDIO_AA54"
$PN"AA54"11;
"VDDIO_Y71"
$PN"Y71"11;
"VDDIO_Y64"
$PN"Y64"11;
"VDDIO_Y57"
$PN"Y57"11;
"VDDIO_V54"
$PN"V54"11;
"VDDIO_U72"
$PN"U72"11;
"VDDIO_U65"
$PN"U65"11;
"VDDIO_U58"
$PN"U58"11;
"VDDIO_P71"
$PN"P71"11;
"VDDIO_P64"
$PN"P64"11;
"VDDIO_P57"
$PN"P57"11;
"VDDIO_P54"
$PN"P54"11;
"VDDIO_L72"
$PN"L72"11;
"VDDIO_L65"
$PN"L65"11;
"VDDIO_L58"
$PN"L58"11;
"VDDIO_K54"
$PN"K54"11;
"VDDIO_H71"
$PN"H71"11;
"VDDIO_H64"
$PN"H64"11;
"VDDIO_H57"
$PN"H57"11;
%"GENOA_SP5"
"23","(-725,4350)","0","pure_quanta","I29";
;
LOCATION"U25"
$SEC"23"
CDS_SEC"23"
PART_TYPE"SMLF"
MATERIAL"IO"
VALUE"SOCKET6096_13568-001"
CDS_LMAN_SYM_OUTLINE"-550,2000,550,-2000"
CDS_LIB"pure_quanta"
NEEDS_NO_SIZE"TRUE"
PART_NUMBER"DGA^6000030";
"TEST6_X3D6"
$PN"B36"0;
"TEST4_CCD15"
$PN"C23"0;
"TEST4_CCD12"
$PN"C58"0;
"TEST5_CCD12"
$PN"C59"0;
"TEST5_CCD15"
$PN"D23"0;
"TEST4_CCD14"
$PN"DF41"0;
"TEST5_CCD14"
$PN"DG42"0;
"TEST4_CCD13"
$PN"DH13"0;
"TEST5_CCD13"
$PN"DH14"0;
"TEST6_X3D7"
$PN"DJ57"0;
"RSVD_A60"
$PN"A60"0;
"RSVD_BD7"
$PN"BD7"0;
"RSVD_D36"
$PN"D36"0;
"RSVD_BD58"
$PN"BD58"0;
"RSVD_BD55"
$PN"BD55"0;
"RSVD_A54"
$PN"A54"0;
"RSVD_A51"
$PN"A51"0;
"RSVD_A50"
$PN"A50"0;
"RSVD_A48"
$PN"A48"0;
"RSVD_C53"
$PN"C53"0;
"RSVD_A45"
$PN"A45"0;
"RSVD_C35"
$PN"C35"0;
"RSVD_D65"
$PN"D65"0;
"RSVD_A42"
$PN"A42"0;
"RSVD_C34"
$PN"C34"0;
"RSVD_D62"
$PN"D62"0;
"RSVD_BD21"
$PN"BD21"0;
"RSVD_A41"
$PN"A41"0;
"RSVD_C31"
$PN"C31"0;
"RSVD_D58"
$PN"D58"0;
"RSVD_BD18"
$PN"BD18"0;
"RSVD_DJ4"
$PN"DJ4"0;
"RSVD_A35"
$PN"A35"0;
"RSVD_B40"
$PN"B40"0;
"RSVD_BD14"
$PN"BD14"0;
"RSVD_DH21"
$PN"DH21"0;
"RSVD_A31"
$PN"A31"0;
"RSVD_D34"
$PN"D34"0;
"RSVD_BD11"
$PN"BD11"0;
"RSVD_DH17"
$PN"DH17"0;
"RSVD_A59"
$PN"A59"0;
"RSVD_D22"
$PN"D22"0;
"RSVD_DG17"
$PN"DG17"0;
"RSVD_A57"
$PN"A57"0;
"RSVD_D11"
$PN"D11"0;
"RSVD_BD4"
$PN"BD4"0;
"RSVD_BD72"
$PN"BD72"0;
"RSVD_A56"
$PN"A56"0;
"RSVD_D8"
$PN"D8"0;
"RSVD_E36"
$PN"E36"0;
"RSVD_BD69"
$PN"BD69"0;
"RSVD_A55"
$PN"A55"0;
"RSVD_D4"
$PN"D4"0;
"RSVD_E33"
$PN"E33"0;
"RSVD_BD65"
$PN"BD65"0;
"RSVD_C54"
$PN"C54"0;
"RSVD_D72"
$PN"D72"0;
"RSVD_BD62"
$PN"BD62"0;
%"VCC_CORE"
"1","(-1675,6625)","0","pure_quanta_power","I40";
;
HDL_POWER"PVDDIO_P0"
CDS_LIB"pure_quanta_power";
"A"11;
%"UNIVERSAL_POWER"
"1","(-1475,825)","0","pure_quanta_power","I41";
;
HDL_POWER"P1V5_BAT"
CDS_LIB"pure_quanta_power";
"A"1;
%"GENOA_SP5"
"24","(-8050,3325)","0","pure_quanta","I42";
;
LOCATION"U25"
$SEC"24"
CDS_SEC"24"
PART_TYPE"SMLF"
MATERIAL"IO"
VALUE"SOCKET6096_13568-001"
CDS_LIB"pure_quanta"
CDS_LMAN_SYM_OUTLINE"-500,3150,500,-3150"
NEEDS_NO_SIZE"TRUE"
PART_NUMBER"DGA^6000030";
"VDDCR_CPU0_AU33"
$PN"AU33"3;
"VDDCR_CPU0_AU25"
$PN"AU25"3;
"VDDCR_CPU0_AU48"
$PN"AU48"3;
"VDDCR_CPU0_AU44"
$PN"AU44"3;
"VDDCR_CPU0_AU29"
$PN"AU29"3;
"VDDCR_CPU0_AT49"
$PN"AT49"3;
"VDDCR_CPU0_AU46"
$PN"AU46"3;
"VDDCR_CPU0_AU42"
$PN"AU42"3;
"VDDCR_CPU0_Y35"
$PN"Y35"3;
"VDDCR_CPU0_Y36"
$PN"Y36"3;
"VDDCR_CPU0_Y40"
$PN"Y40"3;
"VDDCR_CPU0_Y41"
$PN"Y41"3;
"VDDCR_CPU0_AB23"
$PN"AB23"3;
"VDDCR_CPU0_AB24"
$PN"AB24"3;
"VDDCR_CPU0_AB26"
$PN"AB26"3;
"VDDCR_CPU0_AB27"
$PN"AB27"3;
"VDDCR_CPU0_AB29"
$PN"AB29"3;
"VDDCR_CPU0_AB30"
$PN"AB30"3;
"VDDCR_CPU0_AB32"
$PN"AB32"3;
"VDDCR_CPU0_AB33"
$PN"AB33"3;
"VDDCR_CPU0_AB43"
$PN"AB43"3;
"VDDCR_CPU0_AB44"
$PN"AB44"3;
"VDDCR_CPU0_AB46"
$PN"AB46"3;
"VDDCR_CPU0_AB47"
$PN"AB47"3;
"VDDCR_CPU0_AB49"
$PN"AB49"3;
"VDDCR_CPU0_AB50"
$PN"AB50"3;
"VDDCR_CPU0_AB52"
$PN"AB52"3;
"VDDCR_CPU0_AB53"
$PN"AB53"3;
"VDDCR_CPU0_AC35"
$PN"AC35"3;
"VDDCR_CPU0_AC36"
$PN"AC36"3;
"VDDCR_CPU0_AC40"
$PN"AC40"3;
"VDDCR_CPU0_AC41"
$PN"AC41"3;
"VDDCR_CPU0_AF23"
$PN"AF23"3;
"VDDCR_CPU0_AF24"
$PN"AF24"3;
"VDDCR_CPU0_AF26"
$PN"AF26"3;
"VDDCR_CPU0_AF27"
$PN"AF27"3;
"VDDCR_CPU0_AF29"
$PN"AF29"3;
"VDDCR_CPU0_AF30"
$PN"AF30"3;
"VDDCR_CPU0_AF32"
$PN"AF32"3;
"VDDCR_CPU0_AF33"
$PN"AF33"3;
"VDDCR_CPU0_AF43"
$PN"AF43"3;
"VDDCR_CPU0_AF44"
$PN"AF44"3;
"VDDCR_CPU0_AF46"
$PN"AF46"3;
"VDDCR_CPU0_AF47"
$PN"AF47"3;
"VDDCR_CPU0_AF49"
$PN"AF49"3;
"VDDCR_CPU0_AF50"
$PN"AF50"3;
"VDDCR_CPU0_AF52"
$PN"AF52"3;
"VDDCR_CPU0_AF53"
$PN"AF53"3;
"VDDCR_CPU0_AG35"
$PN"AG35"3;
"VDDCR_CPU0_AG36"
$PN"AG36"3;
"VDDCR_CPU0_AG40"
$PN"AG40"3;
"VDDCR_CPU0_AG41"
$PN"AG41"3;
"VDDCR_CPU0_AK23"
$PN"AK23"3;
"VDDCR_CPU0_AK24"
$PN"AK24"3;
"VDDCR_CPU0_AK26"
$PN"AK26"3;
"VDDCR_CPU0_AK27"
$PN"AK27"3;
"VDDCR_CPU0_AK29"
$PN"AK29"3;
"VDDCR_CPU0_AK30"
$PN"AK30"3;
"VDDCR_CPU0_AK32"
$PN"AK32"3;
"VDDCR_CPU0_AK33"
$PN"AK33"3;
"VDDCR_CPU0_AK43"
$PN"AK43"3;
"VDDCR_CPU0_AK44"
$PN"AK44"3;
"VDDCR_CPU0_AK46"
$PN"AK46"3;
"VDDCR_CPU0_AK47"
$PN"AK47"3;
"VDDCR_CPU0_AK49"
$PN"AK49"3;
"VDDCR_CPU0_AK50"
$PN"AK50"3;
"VDDCR_CPU0_AK52"
$PN"AK52"3;
"VDDCR_CPU0_AK53"
$PN"AK53"3;
"VDDCR_CPU0_AL35"
$PN"AL35"3;
"VDDCR_CPU0_AL36"
$PN"AL36"3;
"VDDCR_CPU0_AL40"
$PN"AL40"3;
"VDDCR_CPU0_AL41"
$PN"AL41"3;
"VDDCR_CPU0_AP23"
$PN"AP23"3;
"VDDCR_CPU0_AP24"
$PN"AP24"3;
"VDDCR_CPU0_AP26"
$PN"AP26"3;
"VDDCR_CPU0_AP27"
$PN"AP27"3;
"VDDCR_CPU0_AP29"
$PN"AP29"3;
"VDDCR_CPU0_AP30"
$PN"AP30"3;
"VDDCR_CPU0_AP32"
$PN"AP32"3;
"VDDCR_CPU0_AP33"
$PN"AP33"3;
"VDDCR_CPU0_AP43"
$PN"AP43"3;
"VDDCR_CPU0_AP44"
$PN"AP44"3;
"VDDCR_CPU0_AP46"
$PN"AP46"3;
"VDDCR_CPU0_AP47"
$PN"AP47"3;
"VDDCR_CPU0_AP49"
$PN"AP49"3;
"VDDCR_CPU0_AP50"
$PN"AP50"3;
"VDDCR_CPU0_AP52"
$PN"AP52"3;
"VDDCR_CPU0_AP53"
$PN"AP53"3;
"VDDCR_CPU0_AR23"
$PN"AR23"3;
"VDDCR_CPU0_AR25"
$PN"AR25"3;
"VDDCR_CPU0_AR27"
$PN"AR27"3;
"VDDCR_CPU0_AR29"
$PN"AR29"3;
"VDDCR_CPU0_AR31"
$PN"AR31"3;
"VDDCR_CPU0_AR33"
$PN"AR33"3;
"VDDCR_CPU0_AR35"
$PN"AR35"3;
"VDDCR_CPU0_AR40"
$PN"AR40"3;
"VDDCR_CPU0_AR42"
$PN"AR42"3;
"VDDCR_CPU0_AR44"
$PN"AR44"3;
"VDDCR_CPU0_AR46"
$PN"AR46"3;
"VDDCR_CPU0_AR48"
$PN"AR48"3;
"VDDCR_CPU0_AR50"
$PN"AR50"3;
"VDDCR_CPU0_AT24"
$PN"AT24"3;
"VDDCR_CPU0_AT26"
$PN"AT26"3;
"VDDCR_CPU0_AT28"
$PN"AT28"3;
"VDDCR_CPU0_AT30"
$PN"AT30"3;
"VDDCR_CPU0_AT32"
$PN"AT32"3;
"VDDCR_CPU0_AT34"
$PN"AT34"3;
"VDDCR_CPU0_AT36"
$PN"AT36"3;
"VDDCR_CPU0_AT39"
$PN"AT39"3;
"VDDCR_CPU0_AT41"
$PN"AT41"3;
"VDDCR_CPU0_AT43"
$PN"AT43"3;
"VDDCR_CPU0_AT45"
$PN"AT45"3;
"VDDCR_CPU0_AT47"
$PN"AT47"3;
"VDDCR_CPU0_B19"
$PN"B19"2;
"VDDCR_CPU0_B20"
$PN"B20"2;
"VDDCR_CPU0_B22"
$PN"B22"2;
"VDDCR_CPU0_B23"
$PN"B23"2;
"VDDCR_CPU0_B25"
$PN"B25"2;
"VDDCR_CPU0_B26"
$PN"B26"2;
"VDDCR_CPU0_B28"
$PN"B28"2;
"VDDCR_CPU0_B29"
$PN"B29"2;
"VDDCR_CPU0_B31"
$PN"B31"2;
"VDDCR_CPU0_B32"
$PN"B32"2;
"VDDCR_CPU0_B34"
$PN"B34"2;
"VDDCR_CPU0_B35"
$PN"B35"2;
"VDDCR_CPU0_B41"
$PN"B41"2;
"VDDCR_CPU0_B42"
$PN"B42"2;
"VDDCR_CPU0_B44"
$PN"B44"2;
"VDDCR_CPU0_B45"
$PN"B45"2;
"VDDCR_CPU0_B47"
$PN"B47"2;
"VDDCR_CPU0_B48"
$PN"B48"2;
"VDDCR_CPU0_B50"
$PN"B50"2;
"VDDCR_CPU0_B51"
$PN"B51"2;
"VDDCR_CPU0_B53"
$PN"B53"2;
"VDDCR_CPU0_B54"
$PN"B54"2;
"VDDCR_CPU0_B56"
$PN"B56"2;
"VDDCR_CPU0_B57"
$PN"B57"2;
"VDDCR_CPU0_C20"
$PN"C20"2;
"VDDCR_CPU0_D55"
$PN"D55"2;
"VDDCR_CPU0_D56"
$PN"D56"2;
"VDDCR_CPU0_E22"
$PN"E22"2;
"VDDCR_CPU0_E25"
$PN"E25"2;
"VDDCR_CPU0_E28"
$PN"E28"2;
"VDDCR_CPU0_E31"
$PN"E31"2;
"VDDCR_CPU0_E34"
$PN"E34"2;
"VDDCR_CPU0_E35"
$PN"E35"2;
"VDDCR_CPU0_E42"
$PN"E42"2;
"VDDCR_CPU0_E45"
$PN"E45"2;
"VDDCR_CPU0_E48"
$PN"E48"2;
"VDDCR_CPU0_E51"
$PN"E51"2;
"VDDCR_CPU0_E54"
$PN"E54"2;
"VDDCR_CPU0_F22"
$PN"F22"2;
"VDDCR_CPU0_F25"
$PN"F25"2;
"VDDCR_CPU0_F28"
$PN"F28"2;
"VDDCR_CPU0_F31"
$PN"F31"2;
"VDDCR_CPU0_F34"
$PN"F34"2;
"VDDCR_CPU0_F42"
$PN"F42"2;
"VDDCR_CPU0_F45"
$PN"F45"2;
"VDDCR_CPU0_F48"
$PN"F48"2;
"VDDCR_CPU0_F51"
$PN"F51"2;
"VDDCR_CPU0_F54"
$PN"F54"2;
"VDDCR_CPU0_G35"
$PN"G35"2;
"VDDCR_CPU0_G36"
$PN"G36"2;
"VDDCR_CPU0_G40"
$PN"G40"2;
"VDDCR_CPU0_G41"
$PN"G41"2;
"VDDCR_CPU0_H23"
$PN"H23"2;
"VDDCR_CPU0_H24"
$PN"H24"2;
"VDDCR_CPU0_H26"
$PN"H26"2;
"VDDCR_CPU0_H27"
$PN"H27"2;
"VDDCR_CPU0_H29"
$PN"H29"2;
"VDDCR_CPU0_H30"
$PN"H30"2;
"VDDCR_CPU0_H32"
$PN"H32"2;
"VDDCR_CPU0_H33"
$PN"H33"2;
"VDDCR_CPU0_H43"
$PN"H43"2;
"VDDCR_CPU0_H44"
$PN"H44"2;
"VDDCR_CPU0_H46"
$PN"H46"2;
"VDDCR_CPU0_H47"
$PN"H47"2;
"VDDCR_CPU0_H49"
$PN"H49"2;
"VDDCR_CPU0_H50"
$PN"H50"2;
"VDDCR_CPU0_H52"
$PN"H52"2;
"VDDCR_CPU0_H53"
$PN"H53"2;
"VDDCR_CPU0_J35"
$PN"J35"2;
"VDDCR_CPU0_J36"
$PN"J36"2;
"VDDCR_CPU0_J40"
$PN"J40"2;
"VDDCR_CPU0_J41"
$PN"J41"2;
"VDDCR_CPU0_M23"
$PN"M23"2;
"VDDCR_CPU0_M24"
$PN"M24"2;
"VDDCR_CPU0_M26"
$PN"M26"2;
"VDDCR_CPU0_M27"
$PN"M27"2;
"VDDCR_CPU0_M29"
$PN"M29"2;
"VDDCR_CPU0_M30"
$PN"M30"2;
"VDDCR_CPU0_M32"
$PN"M32"2;
"VDDCR_CPU0_M33"
$PN"M33"2;
"VDDCR_CPU0_M43"
$PN"M43"2;
"VDDCR_CPU0_M44"
$PN"M44"2;
"VDDCR_CPU0_M46"
$PN"M46"2;
"VDDCR_CPU0_M47"
$PN"M47"2;
"VDDCR_CPU0_M49"
$PN"M49"2;
"VDDCR_CPU0_M50"
$PN"M50"2;
"VDDCR_CPU0_M52"
$PN"M52"2;
"VDDCR_CPU0_M53"
$PN"M53"2;
"VDDCR_CPU0_N35"
$PN"N35"2;
"VDDCR_CPU0_N36"
$PN"N36"2;
"VDDCR_CPU0_N40"
$PN"N40"2;
"VDDCR_CPU0_N41"
$PN"N41"2;
"VDDCR_CPU0_T23"
$PN"T23"2;
"VDDCR_CPU0_T24"
$PN"T24"2;
"VDDCR_CPU0_T26"
$PN"T26"2;
"VDDCR_CPU0_T27"
$PN"T27"2;
"VDDCR_CPU0_T29"
$PN"T29"2;
"VDDCR_CPU0_T30"
$PN"T30"2;
"VDDCR_CPU0_T32"
$PN"T32"2;
"VDDCR_CPU0_T33"
$PN"T33"2;
"VDDCR_CPU0_T43"
$PN"T43"2;
"VDDCR_CPU0_T44"
$PN"T44"2;
"VDDCR_CPU0_T46"
$PN"T46"2;
"VDDCR_CPU0_T47"
$PN"T47"2;
"VDDCR_CPU0_T49"
$PN"T49"2;
"VDDCR_CPU0_T50"
$PN"T50"2;
"VDDCR_CPU0_T52"
$PN"T52"2;
"VDDCR_CPU0_T53"
$PN"T53"2;
"VDDCR_CPU0_U35"
$PN"U35"2;
"VDDCR_CPU0_U36"
$PN"U36"2;
"VDDCR_CPU0_U40"
$PN"U40"2;
"VDDCR_CPU0_U41"
$PN"U41"2;
"VDDCR_CPU0_W29"
$PN"W29"2;
"VDDCR_CPU0_W30"
$PN"W30"2;
"VDDCR_CPU0_W32"
$PN"W32"2;
"VDDCR_CPU0_W33"
$PN"W33"2;
"VDDCR_CPU0_W43"
$PN"W43"3;
"VDDCR_CPU0_W44"
$PN"W44"3;
"VDDCR_CPU0_W46"
$PN"W46"3;
"VDDCR_CPU0_W47"
$PN"W47"3;
%"VCC_CORE"
"1","(-7250,6575)","0","pure_quanta_power","I43";
;
HDL_POWER"PVDDCR_CPU0_P0"
CDS_LIB"pure_quanta_power";
"A"3;
%"GENOA_SP5"
"25","(-6075,3350)","0","pure_quanta","I45";
;
LOCATION"U25"
$SEC"25"
CDS_SEC"25"
PART_TYPE"SMLF"
MATERIAL"IO"
VALUE"SOCKET6096_13568-001"
CDS_LMAN_SYM_OUTLINE"-500,3200,500,-3200"
CDS_LIB"pure_quanta"
NEEDS_NO_SIZE"TRUE"
PART_NUMBER"DGA^6000030";
"VDDCR_CPU1_BN46"
$PN"BN46"5;
"VDDCR_CPU1_BN35"
$PN"BN35"5;
"VDDCR_CPU1_BN27"
$PN"BN27"5;
"VDDCR_CPU1_BP32"
$PN"BP32"5;
"VDDCR_CPU1_BP28"
$PN"BP28"5;
"VDDCR_CPU1_BP24"
$PN"BP24"5;
"VDDCR_CPU1_DH51"
$PN"DH51"5;
"VDDCR_CPU1_DH50"
$PN"DH50"5;
"VDDCR_CPU1_DH48"
$PN"DH48"5;
"VDDCR_CPU1_DH47"
$PN"DH47"5;
"VDDCR_CPU1_DH45"
$PN"DH45"5;
"VDDCR_CPU1_DH57"
$PN"DH57"5;
"VDDCR_CPU1_DH56"
$PN"DH56"5;
"VDDCR_CPU1_DH54"
$PN"DH54"5;
"VDDCR_CPU1_DH53"
$PN"DH53"5;
"VDDCR_CPU1_DH44"
$PN"DH44"5;
"VDDCR_CPU1_DH42"
$PN"DH42"5;
"VDDCR_CPU1_DH41"
$PN"DH41"5;
"VDDCR_CPU1_DH35"
$PN"DH35"5;
"VDDCR_CPU1_DH34"
$PN"DH34"5;
"VDDCR_CPU1_DH32"
$PN"DH32"5;
"VDDCR_CPU1_DH31"
$PN"DH31"5;
"VDDCR_CPU1_DH29"
$PN"DH29"5;
"VDDCR_CPU1_DH28"
$PN"DH28"5;
"VDDCR_CPU1_DH26"
$PN"DH26"5;
"VDDCR_CPU1_DH25"
$PN"DH25"5;
"VDDCR_CPU1_DH23"
$PN"DH23"5;
"VDDCR_CPU1_DH22"
$PN"DH22"5;
"VDDCR_CPU1_DH20"
$PN"DH20"5;
"VDDCR_CPU1_DH19"
$PN"DH19"5;
"VDDCR_CPU1_DG57"
$PN"DG57"5;
"VDDCR_CPU1_DG19"
$PN"DG19"5;
"VDDCR_CPU1_DE54"
$PN"DE54"5;
"VDDCR_CPU1_DE51"
$PN"DE51"5;
"VDDCR_CPU1_DE48"
$PN"DE48"5;
"VDDCR_CPU1_DE45"
$PN"DE45"5;
"VDDCR_CPU1_DE42"
$PN"DE42"5;
"VDDCR_CPU1_DE41"
$PN"DE41"5;
"VDDCR_CPU1_DE35"
$PN"DE35"5;
"VDDCR_CPU1_DE34"
$PN"DE34"5;
"VDDCR_CPU1_DE31"
$PN"DE31"5;
"VDDCR_CPU1_DE28"
$PN"DE28"5;
"VDDCR_CPU1_DE25"
$PN"DE25"5;
"VDDCR_CPU1_DE22"
$PN"DE22"5;
"VDDCR_CPU1_DD54"
$PN"DD54"5;
"VDDCR_CPU1_DD51"
$PN"DD51"5;
"VDDCR_CPU1_DD48"
$PN"DD48"5;
"VDDCR_CPU1_DD45"
$PN"DD45"5;
"VDDCR_CPU1_DD42"
$PN"DD42"5;
"VDDCR_CPU1_DD34"
$PN"DD34"5;
"VDDCR_CPU1_DD31"
$PN"DD31"5;
"VDDCR_CPU1_DD28"
$PN"DD28"5;
"VDDCR_CPU1_DD25"
$PN"DD25"5;
"VDDCR_CPU1_DD22"
$PN"DD22"5;
"VDDCR_CPU1_DC41"
$PN"DC41"5;
"VDDCR_CPU1_DC40"
$PN"DC40"5;
"VDDCR_CPU1_DC36"
$PN"DC36"5;
"VDDCR_CPU1_DC35"
$PN"DC35"5;
"VDDCR_CPU1_DB53"
$PN"DB53"5;
"VDDCR_CPU1_DB52"
$PN"DB52"5;
"VDDCR_CPU1_DB50"
$PN"DB50"5;
"VDDCR_CPU1_DB49"
$PN"DB49"5;
"VDDCR_CPU1_DB47"
$PN"DB47"5;
"VDDCR_CPU1_DB46"
$PN"DB46"5;
"VDDCR_CPU1_DB44"
$PN"DB44"5;
"VDDCR_CPU1_DB43"
$PN"DB43"5;
"VDDCR_CPU1_DB33"
$PN"DB33"5;
"VDDCR_CPU1_DB32"
$PN"DB32"5;
"VDDCR_CPU1_DB30"
$PN"DB30"5;
"VDDCR_CPU1_DB29"
$PN"DB29"5;
"VDDCR_CPU1_DB27"
$PN"DB27"5;
"VDDCR_CPU1_DB26"
$PN"DB26"5;
"VDDCR_CPU1_DB24"
$PN"DB24"5;
"VDDCR_CPU1_DB23"
$PN"DB23"5;
"VDDCR_CPU1_DA41"
$PN"DA41"5;
"VDDCR_CPU1_DA40"
$PN"DA40"5;
"VDDCR_CPU1_DA36"
$PN"DA36"5;
"VDDCR_CPU1_DA35"
$PN"DA35"5;
"VDDCR_CPU1_CV53"
$PN"CV53"5;
"VDDCR_CPU1_CV52"
$PN"CV52"5;
"VDDCR_CPU1_CV50"
$PN"CV50"5;
"VDDCR_CPU1_CV49"
$PN"CV49"5;
"VDDCR_CPU1_CV47"
$PN"CV47"5;
"VDDCR_CPU1_CV46"
$PN"CV46"5;
"VDDCR_CPU1_CV44"
$PN"CV44"5;
"VDDCR_CPU1_CV43"
$PN"CV43"5;
"VDDCR_CPU1_CV33"
$PN"CV33"5;
"VDDCR_CPU1_CV32"
$PN"CV32"5;
"VDDCR_CPU1_CV30"
$PN"CV30"5;
"VDDCR_CPU1_CV29"
$PN"CV29"5;
"VDDCR_CPU1_CV27"
$PN"CV27"5;
"VDDCR_CPU1_CV26"
$PN"CV26"5;
"VDDCR_CPU1_CV24"
$PN"CV24"5;
"VDDCR_CPU1_CV23"
$PN"CV23"5;
"VDDCR_CPU1_CU41"
$PN"CU41"5;
"VDDCR_CPU1_CU40"
$PN"CU40"5;
"VDDCR_CPU1_CU36"
$PN"CU36"5;
"VDDCR_CPU1_CU35"
$PN"CU35"5;
"VDDCR_CPU1_CP53"
$PN"CP53"5;
"VDDCR_CPU1_CP52"
$PN"CP52"5;
"VDDCR_CPU1_CP50"
$PN"CP50"5;
"VDDCR_CPU1_CP49"
$PN"CP49"5;
"VDDCR_CPU1_CP47"
$PN"CP47"5;
"VDDCR_CPU1_CP46"
$PN"CP46"5;
"VDDCR_CPU1_CP44"
$PN"CP44"5;
"VDDCR_CPU1_CP43"
$PN"CP43"5;
"VDDCR_CPU1_CP33"
$PN"CP33"5;
"VDDCR_CPU1_CP32"
$PN"CP32"5;
"VDDCR_CPU1_CP30"
$PN"CP30"5;
"VDDCR_CPU1_CP29"
$PN"CP29"5;
"VDDCR_CPU1_CP27"
$PN"CP27"5;
"VDDCR_CPU1_CP26"
$PN"CP26"5;
"VDDCR_CPU1_CP24"
$PN"CP24"5;
"VDDCR_CPU1_CP23"
$PN"CP23"5;
"VDDCR_CPU1_CN41"
$PN"CN41"5;
"VDDCR_CPU1_CN40"
$PN"CN40"5;
"VDDCR_CPU1_CN36"
$PN"CN36"5;
"VDDCR_CPU1_CN35"
$PN"CN35"5;
"VDDCR_CPU1_CL47"
$PN"CL47"5;
"VDDCR_CPU1_CL46"
$PN"CL46"5;
"VDDCR_CPU1_CL44"
$PN"CL44"5;
"VDDCR_CPU1_CL43"
$PN"CL43"5;
"VDDCR_CPU1_CL33"
$PN"CL33"5;
"VDDCR_CPU1_CL32"
$PN"CL32"5;
"VDDCR_CPU1_CL30"
$PN"CL30"4;
"VDDCR_CPU1_CL29"
$PN"CL29"4;
"VDDCR_CPU1_CK41"
$PN"CK41"4;
"VDDCR_CPU1_CK40"
$PN"CK40"4;
"VDDCR_CPU1_CK36"
$PN"CK36"4;
"VDDCR_CPU1_CK35"
$PN"CK35"4;
"VDDCR_CPU1_CH53"
$PN"CH53"4;
"VDDCR_CPU1_CH52"
$PN"CH52"4;
"VDDCR_CPU1_CH50"
$PN"CH50"4;
"VDDCR_CPU1_CH49"
$PN"CH49"4;
"VDDCR_CPU1_CH47"
$PN"CH47"4;
"VDDCR_CPU1_CH46"
$PN"CH46"4;
"VDDCR_CPU1_CH44"
$PN"CH44"4;
"VDDCR_CPU1_CH43"
$PN"CH43"4;
"VDDCR_CPU1_CH33"
$PN"CH33"4;
"VDDCR_CPU1_CH32"
$PN"CH32"4;
"VDDCR_CPU1_CH30"
$PN"CH30"4;
"VDDCR_CPU1_CH29"
$PN"CH29"4;
"VDDCR_CPU1_CH27"
$PN"CH27"4;
"VDDCR_CPU1_CH26"
$PN"CH26"4;
"VDDCR_CPU1_CH24"
$PN"CH24"4;
"VDDCR_CPU1_CH23"
$PN"CH23"4;
"VDDCR_CPU1_CG41"
$PN"CG41"4;
"VDDCR_CPU1_CG40"
$PN"CG40"4;
"VDDCR_CPU1_CG36"
$PN"CG36"4;
"VDDCR_CPU1_CG35"
$PN"CG35"4;
"VDDCR_CPU1_CD53"
$PN"CD53"4;
"VDDCR_CPU1_CD52"
$PN"CD52"4;
"VDDCR_CPU1_CD50"
$PN"CD50"4;
"VDDCR_CPU1_CD49"
$PN"CD49"4;
"VDDCR_CPU1_CD47"
$PN"CD47"4;
"VDDCR_CPU1_CD46"
$PN"CD46"4;
"VDDCR_CPU1_CD44"
$PN"CD44"4;
"VDDCR_CPU1_CD43"
$PN"CD43"4;
"VDDCR_CPU1_CD33"
$PN"CD33"4;
"VDDCR_CPU1_CD32"
$PN"CD32"4;
"VDDCR_CPU1_CD30"
$PN"CD30"4;
"VDDCR_CPU1_CD29"
$PN"CD29"4;
"VDDCR_CPU1_CD27"
$PN"CD27"4;
"VDDCR_CPU1_CD26"
$PN"CD26"4;
"VDDCR_CPU1_CD24"
$PN"CD24"4;
"VDDCR_CPU1_CD23"
$PN"CD23"4;
"VDDCR_CPU1_CC41"
$PN"CC41"4;
"VDDCR_CPU1_CC40"
$PN"CC40"4;
"VDDCR_CPU1_CC36"
$PN"CC36"4;
"VDDCR_CPU1_CC35"
$PN"CC35"4;
"VDDCR_CPU1_BY53"
$PN"BY53"4;
"VDDCR_CPU1_BY52"
$PN"BY52"4;
"VDDCR_CPU1_BY50"
$PN"BY50"4;
"VDDCR_CPU1_BY49"
$PN"BY49"4;
"VDDCR_CPU1_BY47"
$PN"BY47"4;
"VDDCR_CPU1_BY46"
$PN"BY46"4;
"VDDCR_CPU1_BY44"
$PN"BY44"4;
"VDDCR_CPU1_BY43"
$PN"BY43"4;
"VDDCR_CPU1_BY33"
$PN"BY33"4;
"VDDCR_CPU1_BY32"
$PN"BY32"4;
"VDDCR_CPU1_BY30"
$PN"BY30"4;
"VDDCR_CPU1_BY29"
$PN"BY29"4;
"VDDCR_CPU1_BY27"
$PN"BY27"4;
"VDDCR_CPU1_BY26"
$PN"BY26"4;
"VDDCR_CPU1_BY24"
$PN"BY24"4;
"VDDCR_CPU1_BY23"
$PN"BY23"4;
"VDDCR_CPU1_BW41"
$PN"BW41"4;
"VDDCR_CPU1_BW40"
$PN"BW40"4;
"VDDCR_CPU1_BW36"
$PN"BW36"4;
"VDDCR_CPU1_BW35"
$PN"BW35"4;
"VDDCR_CPU1_BT53"
$PN"BT53"4;
"VDDCR_CPU1_BT52"
$PN"BT52"4;
"VDDCR_CPU1_BT50"
$PN"BT50"4;
"VDDCR_CPU1_BT49"
$PN"BT49"4;
"VDDCR_CPU1_BT47"
$PN"BT47"4;
"VDDCR_CPU1_BT46"
$PN"BT46"4;
"VDDCR_CPU1_BT44"
$PN"BT44"4;
"VDDCR_CPU1_BT43"
$PN"BT43"4;
"VDDCR_CPU1_BT33"
$PN"BT33"4;
"VDDCR_CPU1_BT32"
$PN"BT32"4;
"VDDCR_CPU1_BT30"
$PN"BT30"4;
"VDDCR_CPU1_BT29"
$PN"BT29"4;
"VDDCR_CPU1_BT27"
$PN"BT27"4;
"VDDCR_CPU1_BT26"
$PN"BT26"4;
"VDDCR_CPU1_BT24"
$PN"BT24"4;
"VDDCR_CPU1_BT23"
$PN"BT23"4;
"VDDCR_CPU1_BR52"
$PN"BR52"4;
"VDDCR_CPU1_BR50"
$PN"BR50"4;
"VDDCR_CPU1_BR48"
$PN"BR48"4;
"VDDCR_CPU1_BR46"
$PN"BR46"4;
"VDDCR_CPU1_BR44"
$PN"BR44"4;
"VDDCR_CPU1_BR42"
$PN"BR42"4;
"VDDCR_CPU1_BR40"
$PN"BR40"4;
"VDDCR_CPU1_BR35"
$PN"BR35"4;
"VDDCR_CPU1_BR33"
$PN"BR33"4;
"VDDCR_CPU1_BR31"
$PN"BR31"4;
"VDDCR_CPU1_BR29"
$PN"BR29"4;
"VDDCR_CPU1_BR27"
$PN"BR27"4;
"VDDCR_CPU1_BR25"
$PN"BR25"4;
"VDDCR_CPU1_BR23"
$PN"BR23"4;
"VDDCR_CPU1_BP49"
$PN"BP49"4;
"VDDCR_CPU1_BP47"
$PN"BP47"4;
"VDDCR_CPU1_BP45"
$PN"BP45"4;
"VDDCR_CPU1_BP43"
$PN"BP43"4;
"VDDCR_CPU1_BP41"
$PN"BP41"4;
"VDDCR_CPU1_BP39"
$PN"BP39"4;
"VDDCR_CPU1_BP36"
$PN"BP36"4;
"VDDCR_CPU1_BP34"
$PN"BP34"4;
"VDDCR_CPU1_BP30"
$PN"BP30"4;
"VDDCR_CPU1_BP26"
$PN"BP26"4;
"VDDCR_CPU1_BN50"
$PN"BN50"4;
"VDDCR_CPU1_BN42"
$PN"BN42"4;
"VDDCR_CPU1_BN31"
$PN"BN31"4;
%"VCC_CORE"
"1","(-5275,6475)","0","pure_quanta_power","I46";
;
HDL_POWER"PVDDCR_CPU1_P0"
CDS_LIB"pure_quanta_power";
"A"5;
%"VCC_CORE"
"1","(-6900,6225)","0","pure_quanta_power","I47";
;
HDL_POWER"PVDDCR_CPU1_P0"
CDS_LIB"pure_quanta_power";
"A"4;
%"GENOA_SP5"
"26","(-4250,4575)","0","pure_quanta","I50";
;
LOCATION"U25"
$SEC"26"
CDS_SEC"26"
PART_TYPE"SMLF"
MATERIAL"IO"
VALUE"SOCKET6096_13568-001"
CDS_LMAN_SYM_OUTLINE"-450,1650,450,-1650"
NEEDS_NO_SIZE"TRUE"
CDS_LIB"pure_quanta"
PART_NUMBER"DGA^6000030";
"VDDCR_SOC_BG22"
$PN"BG22"10;
"VDDCR_SOC_BG24"
$PN"BG24"10;
"VDDCR_SOC_BG26"
$PN"BG26"10;
"VDDCR_SOC_BG28"
$PN"BG28"10;
"VDDCR_SOC_BG48"
$PN"BG48"10;
"VDDCR_SOC_BH23"
$PN"BH23"10;
"VDDCR_SOC_BH25"
$PN"BH25"10;
"VDDCR_SOC_BH48"
$PN"BH48"10;
"VDDCR_SOC_BJ4"
$PN"BJ4"10;
"VDDCR_SOC_BJ11"
$PN"BJ11"10;
"VDDCR_SOC_BJ48"
$PN"BJ48"10;
"VDDCR_SOC_BM5"
$PN"BM5"10;
"VDDCR_SOC_BF48"
$PN"BF48"10;
"VDDCR_SOC_BF27"
$PN"BF27"10;
"VDDCR_SOC_BF25"
$PN"BF25"10;
"VDDCR_SOC_BF23"
$PN"BF23"10;
"VDDCR_SOC_BD48"
$PN"BD48"10;
"VDDCR_SOC_BD28"
$PN"BD28"10;
"VDDCR_SOC_BD26"
$PN"BD26"10;
"VDDCR_SOC_BD24"
$PN"BD24"10;
"VDDCR_SOC_BD22"
$PN"BD22"10;
"VDDCR_SOC_BD19"
$PN"BD19"10;
"VDDCR_SOC_BD12"
$PN"BD12"10;
"VDDCR_SOC_BD5"
$PN"BD5"10;
"VDDCR_SOC_BC48"
$PN"BC48"10;
"VDDCR_SOC_BC27"
$PN"BC27"10;
"VDDCR_SOC_BC25"
$PN"BC25"10;
"VDDCR_SOC_BC23"
$PN"BC23"10;
"VDDCR_SOC_BB49"
$PN"BB49"10;
"VDDCR_SOC_BB28"
$PN"BB28"10;
"VDDCR_SOC_BB26"
$PN"BB26"10;
"VDDCR_SOC_BB24"
$PN"BB24"10;
"VDDCR_SOC_BB22"
$PN"BB22"10;
"VDDCR_SOC_BA48"
$PN"BA48"10;
"VDDCR_SOC_BA27"
$PN"BA27"10;
"VDDCR_SOC_BA25"
$PN"BA25"10;
"VDDCR_SOC_BA23"
$PN"BA23"10;
"VDDCR_SOC_BA18"
$PN"BA18"10;
"VDDCR_SOC_BA11"
$PN"BA11"10;
"VDDCR_SOC_BA4"
$PN"BA4"10;
"VDDCR_SOC_AY49"
$PN"AY49"10;
"VDDCR_SOC_AY28"
$PN"AY28"10;
"VDDCR_SOC_AY26"
$PN"AY26"10;
"VDDCR_SOC_AY24"
$PN"AY24"10;
"VDDCR_SOC_AY22"
$PN"AY22"10;
"VDDCR_SOC_AW48"
$PN"AW48"10;
"VDDCR_SOC_AW27"
$PN"AW27"10;
"VDDCR_SOC_AW25"
$PN"AW25"10;
"VDDCR_SOC_AW23"
$PN"AW23"10;
"VDDCR_SOC_AV47"
$PN"AV47"10;
"VDDCR_SOC_AV45"
$PN"AV45"10;
"VDDCR_SOC_AV43"
$PN"AV43"10;
"VDDCR_SOC_AV41"
$PN"AV41"6;
"VDDCR_SOC_AV39"
$PN"AV39"6;
"VDDCR_SOC_AV36"
$PN"AV36"6;
"VDDCR_SOC_AV34"
$PN"AV34"6;
"VDDCR_SOC_AV32"
$PN"AV32"6;
"VDDCR_SOC_AV30"
$PN"AV30"6;
"VDDCR_SOC_AV28"
$PN"AV28"6;
"VDDCR_SOC_AV26"
$PN"AV26"6;
"VDDCR_SOC_AV24"
$PN"AV24"6;
"VDDCR_SOC_AV22"
$PN"AV22"6;
"VDDCR_SOC_AV19"
$PN"AV19"6;
"VDDCR_SOC_AV12"
$PN"AV12"6;
"VDDCR_SOC_AV5"
$PN"AV5"6;
"VDDCR_SOC_AU40"
$PN"AU40"6;
"VDDCR_SOC_AU35"
$PN"AU35"6;
"VDDCR_SOC_AU31"
$PN"AU31"6;
"VDDCR_SOC_AU27"
$PN"AU27"6;
"VDDCR_SOC_AU23"
$PN"AU23"6;
"VDDCR_SOC_AT22"
$PN"AT22"6;
"VDDCR_SOC_AR18"
$PN"AR18"6;
"VDDCR_SOC_AR11"
$PN"AR11"6;
"VDDCR_SOC_AR4"
$PN"AR4"6;
"VDDCR_SOC_AM22"
$PN"AM22"6;
"VDDCR_SOC_AM19"
$PN"AM19"6;
"VDDCR_SOC_AM12"
$PN"AM12"6;
"VDDCR_SOC_AM5"
$PN"AM5"6;
"VDDCR_SOC_AJ18"
$PN"AJ18"6;
"VDDCR_SOC_AJ11"
$PN"AJ11"6;
"VDDCR_SOC_AJ4"
$PN"AJ4"6;
"VDDCR_SOC_AH22"
$PN"AH22"6;
"VDDCR_SOC_AF19"
$PN"AF19"6;
"VDDCR_SOC_AF12"
$PN"AF12"6;
"VDDCR_SOC_AF5"
$PN"AF5"6;
"VDDCR_SOC_AD22"
$PN"AD22"6;
"VDDCR_SOC_AC18"
$PN"AC18"6;
"VDDCR_SOC_AC11"
$PN"AC11"6;
"VDDCR_SOC_AC4"
$PN"AC4"6;
"VDDCR_SOC_AA22"
$PN"AA22"6;
"VDDCR_SOC_Y19"
$PN"Y19"6;
"VDDCR_SOC_Y12"
$PN"Y12"6;
"VDDCR_SOC_Y5"
$PN"Y5"6;
"VDDCR_SOC_V22"
$PN"V22"6;
"VDDCR_SOC_U18"
$PN"U18"6;
"VDDCR_SOC_U11"
$PN"U11"6;
"VDDCR_SOC_U4"
$PN"U4"6;
"VDDCR_SOC_P22"
$PN"P22"6;
"VDDCR_SOC_P19"
$PN"P19"6;
"VDDCR_SOC_P12"
$PN"P12"6;
"VDDCR_SOC_P5"
$PN"P5"6;
"VDDCR_SOC_L18"
$PN"L18"6;
"VDDCR_SOC_L11"
$PN"L11"6;
"VDDCR_SOC_L4"
$PN"L4"6;
"VDDCR_SOC_K22"
$PN"K22"6;
"VDDCR_SOC_H19"
$PN"H19"6;
"VDDCR_SOC_H12"
$PN"H12"6;
"VDDCR_SOC_H5"
$PN"H5"6;
"VDDCR_SOC_E11"
$PN"E11"6;
"VDDCR_SOC_E4"
$PN"E4"6;
"VDDCR_SOC_C4"
$PN"C4"6;
"VDDCR_SOC_B5"
$PN"B5"6;
%"VCC_CORE"
"1","(-8900,6575)","0","pure_quanta_power","I51";
;
HDL_POWER"PVDDCR_CPU0_P0"
CDS_LIB"pure_quanta_power";
"A"2;
%"VCC_CORE"
"1","(-3300,6600)","0","pure_quanta_power","I52";
;
HDL_POWER"PVDD11_S3_P0"
CDS_LIB"pure_quanta_power";
"A"9;
%"UNIVERSAL_POWER"
"1","(-3475,2825)","0","pure_quanta_power","I53";
;
HDL_POWER"PVDD18_S5_P0"
CDS_LIB"pure_quanta_power";
"A"8;
%"UNIVERSAL_POWER"
"1","(-3475,1075)","0","pure_quanta_power","I55";
;
HDL_POWER"PVDD_33_S5"
CDS_LIB"pure_quanta_power";
"A"7;
%"VCC_CORE"
"1","(-3500,6150)","0","pure_quanta_power","I56";
;
HDL_POWER"PVDDCR_SOC_P0"
CDS_LIB"pure_quanta_power";
"A"10;
%"VCC_CORE"
"1","(-4975,6150)","0","pure_quanta_power","I57";
;
HDL_POWER"PVDDCR_SOC_P0"
CDS_LIB"pure_quanta_power";
"A"6;
END.
